#ISCELL
  mstr_misc dns *
  *
#ISCELL
  mstr_symbols design_note *
  *
#ISCELL
  mstr_symbols intel_corp_bpage *
  *
#ISCELL
  mstr_standard offpage *
  page201_i1
#ISCELL
  mstr_standard offpage *
  page201_i10
#CELL
  mstr_discrete res *
  page201_i102
#CELL
  mstr_discrete res *
  page201_i103
#CELL
  mstr_discrete res *
  page201_i109
#ISCELL
  mstr_standard offpage *
  page201_i11
#CELL
  mstr_discrete res *
  page201_i110
#CELL
  mstr_discrete res *
  page201_i111
#ISCELL
  mstr_symbols p3v3_stby *
  page201_i112
#ISCELL
  mstr_symbols p3v3_stby *
  page201_i113
#ISCELL
  mstr_symbols p3v3_stby *
  page201_i115
#CELL
  mstr_discrete res *
  page201_i116
#ISCELL
  mstr_standard offpage *
  page201_i118
#ISCELL
  mstr_standard offpage *
  page201_i12
#CELL
  mstr_discrete res *
  page201_i120
#CELL
  mstr_discrete res *
  page201_i121
#ISCELL
  mstr_symbols gnd *
  page201_i123
#CELL
  mstr_discrete res *
  page201_i124
#CELL
  mstr_discrete cap *
  page201_i125
#ISCELL
  mstr_symbols gnd *
  page201_i126
#CELL
  mstr_discrete res *
  page201_i127
#CELL
  mstr_discrete res *
  page201_i128
#CELL
  mstr_discrete res *
  page201_i131
#CELL
  mstr_discrete res *
  page201_i132
#ISCELL
  mstr_standard offpage *
  page201_i14
#ISCELL
  mstr_standard offpage *
  page201_i15
#CELL
  mstr_controller pxe1610b *
  page201_i155
#CELL
  w_hdl sc22p50v2jn-4gp *
  page201_i168
#CELL
  w_hdl sc22p50v2jn-4gp *
  page201_i169
#ISCELL
  mstr_standard offpage *
  page201_i17
#CELL
  w_hdl sc22p50v2jn-4gp *
  page201_i170
#CELL
  w_hdl sc22p50v2jn-4gp *
  page201_i171
#CELL
  w_hdl sc22p50v2jn-4gp *
  page201_i172
#CELL
  w_hdl sc22p50v2jn-4gp *
  page201_i173
#ISCELL
  mstr_symbols pvccio_cpu0 *
  page201_i18
#CELL
  mstr_discrete res *
  page201_i180
#CELL
  mstr_discrete res *
  page201_i182
#CELL
  mstr_discrete res *
  page201_i183
#CELL
  mstr_discrete res *
  page201_i184
#CELL
  mstr_discrete res *
  page201_i185
#CELL
  mstr_discrete res *
  page201_i186
#CELL
  mstr_discrete res *
  page201_i187
#CELL
  mstr_discrete res *
  page201_i189
#CELL
  mstr_discrete res *
  page201_i190
#CELL
  w_hdl pin-con3-27-gp *
  page201_i191
#CELL
  dev_discrete cap_a *
  page201_i192
#ISCELL
  mstr_standard offpage *
  page201_i2
#CELL
  mstr_discrete res *
  page201_i22
#CELL
  mstr_discrete res *
  page201_i25
#CELL
  mstr_discrete res *
  page201_i26
#CELL
  mstr_discrete res *
  page201_i27
#ISCELL
  mstr_symbols gnd *
  page201_i29
#ISCELL
  mstr_standard offpage *
  page201_i3
#CELL
  dev_discrete cap_a *
  page201_i30
#CELL
  dev_discrete cap_a *
  page201_i32
#ISCELL
  mstr_symbols gnd *
  page201_i33
#ISCELL
  mstr_symbols gnd *
  page201_i35
#ISCELL
  mstr_symbols gnd *
  page201_i36
#CELL
  dev_discrete cap_a *
  page201_i37
#ISCELL
  mstr_symbols gnd *
  page201_i38
#CELL
  dev_discrete cap_a *
  page201_i39
#ISCELL
  mstr_standard offpage *
  page201_i4
#CELL
  mstr_discrete res *
  page201_i40
#ISCELL
  mstr_symbols gnd *
  page201_i48
#ISCELL
  mstr_standard offpage *
  page201_i5
#ISCELL
  mstr_symbols gnd *
  page201_i50
#ISCELL
  mstr_symbols pvccio_cpu0 *
  page201_i51
#ISCELL
  mstr_symbols vcc_core *
  page201_i53
#CELL
  mstr_discrete res *
  page201_i54
#CELL
  mstr_discrete res *
  page201_i55
#CELL
  mstr_discrete res *
  page201_i56
#ISCELL
  mstr_symbols gnd *
  page201_i58
#ISCELL
  mstr_standard offpage *
  page201_i6
#ISCELL
  mstr_symbols gnd *
  page201_i61
#CELL
  mstr_discrete cap *
  page201_i64
#CELL
  mstr_discrete cap *
  page201_i66
#ISCELL
  mstr_symbols gnd *
  page201_i67
#CELL
  mstr_discrete cap *
  page201_i68
#ISCELL
  mstr_symbols gnd *
  page201_i69
#ISCELL
  mstr_standard offpage *
  page201_i7
#CELL
  mstr_discrete cap *
  page201_i70
#ISCELL
  mstr_standard offpage *
  page201_i73
#ISCELL
  mstr_standard offpage *
  page201_i74
#ISCELL
  mstr_standard offpage *
  page201_i75
#ISCELL
  mstr_standard offpage *
  page201_i76
#ISCELL
  mstr_standard offpage *
  page201_i77
#ISCELL
  mstr_standard offpage *
  page201_i78
#ISCELL
  mstr_standard offpage *
  page201_i79
#ISCELL
  mstr_standard offpage *
  page201_i8
#ISCELL
  mstr_standard offpage *
  page201_i80
#ISCELL
  mstr_standard offpage *
  page201_i82
#ISCELL
  mstr_standard offpage *
  page201_i83
#ISCELL
  mstr_standard offpage *
  page201_i84
#ISCELL
  mstr_standard offpage *
  page201_i85
#ISCELL
  mstr_standard offpage *
  page201_i87
#ISCELL
  mstr_standard offpage *
  page201_i88
#ISCELL
  mstr_standard offpage *
  page201_i89
#ISCELL
  mstr_standard offpage *
  page201_i9
#ISCELL
  mstr_standard offpage *
  page201_i90
#ISCELL
  mstr_standard offpage *
  page201_i91
#ISCELL
  mstr_standard offpage *
  page201_i92
#ISCELL
  mstr_standard offpage *
  page201_i93
#ISCELL
  mstr_standard offpage *
  page201_i94
#ISCELL
  mstr_standard offpage *
  page201_i96
#ISCELL
  mstr_standard offpage *
  page201_i97
#CELL
  mstr_discrete res *
  page201_i98
